;LEADER: 12 
;HEADER: 
;CODE  : ASCII 
;FILE  : 9332_F0TG_MB_C_V02_0417_0820-bd-18-13.drl for backdrilling ... from layer BOTTOM to layer GND5
;DESIGN: 9332_F0TG_MB_C_V02_0417_0820.brd
;MUST-NOT-CUT-LAYER = IN4,  MAX_DRILL_DEPTH = 30.80 MILS,  MFG_STUB_LENGTH = 0.00 MILS
;   BackdrillSize 1. = 14.800000 Tolerance = +0.000000/-0.000000 NON_PLATED MILS Quantity = 936
;   BackdrillSize 2. = 17.000000 Tolerance = +0.000000/-0.000000 NON_PLATED MILS Quantity = 848
;   BackdrillSize 3. = 21.170000 Tolerance = +0.000000/-0.000000 NON_PLATED MILS Quantity = 128
%
G90
X0360311Y1533336
X0355587Y1533336
X0350862Y1533336
R02X-0004724
X0336689Y1533336
X0331965Y1533336
X0327240Y1533336
X0322516Y1533336
X0388658Y1533336
X0383933Y1533336
X0379209Y1533336
X0374484Y1533336
X0369760Y1533336
X0365036Y1533336
X0317792Y1533336
X0358736Y1530608
R02X-0004724
X0344563Y1530608
X0339839Y1530608
X0335114Y1530608
R02X-0004724
X0320941Y1530608
X0387083Y1530608
X0382359Y1530608
X0377634Y1530608
X0372910Y1530608
X0368185Y1530608
X0363461Y1530608
X0316217Y1530608
X0410477Y0968915
X0410477Y0962537
X0410477Y0975293
X0421579Y0968915
X0421579Y0962537
X0421579Y0975293
X0430831Y0965726
X0430831Y0959348
X0430831Y0972104
X0388272Y0968915
X0388272Y0962537
X0388272Y0975293
X0399374Y0968915
X0399374Y0962537
X0399374Y0975293
X0430831Y0978482
X0406776Y0968915
X0406776Y0962537
X0406776Y0975293
X0417878Y0968915
X0417878Y0962537
X0417878Y0975293
X0427130Y0965726
X0427130Y0959348
X0427130Y0972104
X0384571Y0968915
X0384571Y0962537
X0384571Y0975293
X0395673Y0968915
X0395673Y0962537
X0395673Y0975293
X0427130Y0978482
X1446987Y1088646
X1446987Y1095024
X1435885Y1082268
X1426633Y1098213
X1426633Y1091835
X1469192Y1088646
X1469192Y1095024
X1469192Y1082268
X1458090Y1088646
X1458090Y1095024
X1458090Y1082268
X1426633Y1085457
X1450688Y1088646
X1450688Y1095024
X1439586Y1082268
X1430334Y1098213
X1430334Y1091835
X1472893Y1088646
X1472893Y1095024
X1472893Y1082268
X1461791Y1088646
X1461791Y1095024
X1461791Y1082268
X1430334Y1085457
X0470845Y1088647
X0470845Y1095025
X0470845Y1082269
X0459743Y1088647
R02Y0006378
X0459743Y1082269
X0450491Y1098214
X0450491Y1091836
X0493050Y1088647
X0493050Y1095025
X0493050Y1082269
X0481948Y1088647
X0481948Y1095025
X0481948Y1082269
X0450491Y1085458
X0474546Y1088647
X0474546Y1095025
X0474546Y1082269
X0463444Y1088647
R02Y0006378
X0463444Y1082269
X0454192Y1098214
X0454192Y1091836
X0496751Y1088647
X0496751Y1095025
X0496751Y1082269
X0485649Y1088647
X0485649Y1095025
X0485649Y1082269
X0454192Y1085458
X0422760Y1088647
X0360311Y1519698
X0411658Y1082269
X0355587Y1519698
X0411658Y1095025
X0350862Y1519698
X0411658Y1088647
X0346138Y1519698
X0400555Y1082269
X0341414Y1519698
X0400555Y1095025
X0336689Y1519698
X0400555Y1088647
X0331965Y1519698
X0389453Y1082269
X0327240Y1519698
X0389453Y1095025
X0322516Y1519698
X0432012Y1085458
X0388658Y1519698
X0432012Y1091836
X0383933Y1519698
X0432012Y1098214
X0379209Y1519698
X0422760Y1082269
X0374484Y1519698
X0422760Y1101403
X0369760Y1519698
X0422760Y1095025
X0365036Y1519698
X0389453Y1088647
X0317792Y1519698
X0419059Y1088647
X0358736Y1516970
X0407957Y1082269
X0354012Y1516970
X0407957Y1095025
X0349288Y1516970
X0407957Y1088647
X0344563Y1516970
X0396855Y1082269
X0339839Y1516970
X0396855Y1095025
X0335114Y1516970
X0396855Y1088647
X0330390Y1516970
X0385752Y1082269
X0325666Y1516970
X0385752Y1095025
X0320941Y1516970
X0428311Y1085458
X0387083Y1516970
X0428311Y1091836
X0382359Y1516970
X0428311Y1098214
X0377634Y1516970
X0419059Y1082269
X0372910Y1516970
X0419059Y1101403
X0368185Y1516970
X0419059Y1095025
X0363461Y1516970
X0385752Y1088647
X0316217Y1516970
X1446987Y1082268
X1435885Y1088646
R02Y0006378
X1450688Y1082268
X1439586Y1088646
R02Y0006378
X1398902Y1088646
X1368184Y1552698
X1387800Y1082268
X1363460Y1552698
X1387800Y1095024
X1358735Y1552698
X1387800Y1088646
X1354011Y1552698
X1376697Y1082268
X1349287Y1552698
X1376697Y1095024
X1344562Y1552698
X1376697Y1088646
X1339838Y1552698
X1365595Y1082268
X1335113Y1552698
X1365595Y1095024
X1330389Y1552698
X1408154Y1085457
X1396531Y1552698
X1408154Y1091835
X1391806Y1552698
X1408154Y1098213
X1387082Y1552698
X1398902Y1082268
X1382357Y1552698
X1398902Y1101402
X1377633Y1552698
X1398902Y1095024
X1372909Y1552698
X1365595Y1088646
X1325665Y1552698
X1395201Y1088646
X1366609Y1549970
X1384099Y1082268
X1361885Y1549970
X1384099Y1095024
X1357161Y1549970
X1384099Y1088646
X1352436Y1549970
X1372997Y1082268
X1347712Y1549970
X1372997Y1095024
X1342987Y1549970
X1372997Y1088646
X1338263Y1549970
X1361894Y1082268
X1333539Y1549970
X1361894Y1095024
X1328814Y1549970
X1404453Y1085457
X1394956Y1549970
X1404453Y1091835
X1390232Y1549970
X1404453Y1098213
X1385507Y1549970
X1395201Y1082268
X1380783Y1549970
X1395201Y1101402
X1376058Y1549970
X1395201Y1095024
X1371334Y1549970
X1361894Y1088646
X1324090Y1549970
X1434704Y0968914
X1445806Y0975292
X1445806Y0962536
X1445806Y0968914
X1456909Y0975292
X1456909Y0962536
X1456909Y0968914
X1468011Y0975292
X1468011Y0962536
X1425452Y0978481
X1425452Y0972103
X1425452Y0959347
X1425452Y0965725
X1434704Y0975292
X1434704Y0962536
X1468011Y0968914
X1438405Y0968914
X1449507Y0975292
X1449507Y0962536
X1449507Y0968914
X1460609Y0975292
X1460609Y0962536
X1460609Y0968914
X1471712Y0975292
X1471712Y0962536
X1429153Y0978481
X1429153Y0972103
X1429153Y0959347
X1429153Y0965725
X1438405Y0975292
X1438405Y0962536
X1471712Y0968914
X0550412Y1053568
X0544861Y1044001
X0550412Y1066324
X0543011Y1149237
X0543011Y1130103
X0543011Y1110970
R02Y-0019134
X0550412Y1142859
X0550412Y1123726
X0550412Y1104592
X0550412Y1085458
X0548562Y1069513
X0544861Y1146048
X0544861Y1126915
X0544861Y1107781
R02Y-0019134
X0548562Y1146048
X0548562Y1126915
X0548562Y1107781
X0548562Y1088647
X0544861Y1101403
X0550412Y1098214
X0543011Y1098214
X0548562Y1095025
X0544861Y1095025
X0550412Y1091836
X0543011Y1085458
X0550412Y1155615
X0548562Y1152426
X0548562Y1082269
X0544861Y1152426
X0550412Y1149237
X0543011Y1142859
X0548562Y1139670
X0544861Y1139670
X0550412Y1136481
X0543011Y1136481
X0548562Y1133293
X0544861Y1133293
X0550412Y1130103
X0544861Y1082269
X0543011Y1123726
X0548562Y1120537
X0544861Y1120537
X0550412Y1117348
X0543011Y1117348
X0548562Y1114159
X0544861Y1114159
X0550412Y1110970
X0543011Y1104592
X0548562Y1101403
X0550412Y1079080
X0548562Y1050379
X0543011Y1047190
X0543011Y1066324
X0548562Y1063135
X0544861Y1063135
X0550412Y1059946
X0543011Y1079080
X0548562Y1075891
X0544861Y1075891
X0550412Y1072702
X0550412Y1040812
X0543011Y1040812
X0544861Y1037623
X0548562Y1037623
X0550412Y1034434
X0543011Y1034434
X0544861Y1031245
X0544861Y1050379
X0543680Y1007183
X0543680Y0975293
X0543680Y0956159
R02Y-0019134
X0543680Y0898758
X0547381Y0968915
R03Y-0019134
X0547381Y0892380
X0541830Y0972104
R03Y-0019134
X0541830Y0895569
X0549231Y0972104
R03Y-0019134
X0549231Y0895569
X0541830Y0908325
X0547381Y0905135
X0543680Y0905135
X0549231Y0901947
X0541830Y0901947
X0547381Y0898758
X0543680Y0892380
X0543680Y0962537
X0549231Y0959348
X0549231Y0889191
X0541830Y0959348
X0547381Y0956159
X0543680Y0949781
X0549231Y0946592
X0541830Y0946592
X0547381Y0943403
X0543680Y0943403
X0549231Y0940214
X0541830Y0940214
X0547381Y0937025
X0541830Y0889191
X0543680Y0930647
X0549231Y0927458
X0541830Y0927458
X0547381Y0924269
X0543680Y0924269
X0549231Y0921080
X0541830Y0921080
X0547381Y0917891
X0543680Y0911513
X0549231Y0908325
X0547381Y0886002
X0541830Y0991238
X0547381Y0988049
X0543680Y0981671
X0549231Y0978482
X0541830Y0978482
X0547381Y0975293
X0543680Y0968915
X0549231Y0965726
X0541830Y0965726
X0547381Y0962537
X0541830Y1003994
X0549231Y1003994
X0547381Y1000805
X0543680Y1000805
X0541830Y0997616
X0549231Y0997616
X0547381Y0994427
X0543680Y0988049
X0547381Y1007183
X0549231Y1010372
X0541830Y0984860
X1526554Y1053567
X1521003Y1044000
X1526554Y1066323
X1519153Y1149236
X1519153Y1130102
X1519153Y1110969
R02Y-0019134
X1526554Y1142858
X1526554Y1123725
X1526554Y1104591
X1526554Y1085457
X1524704Y1069512
X1521003Y1146047
X1521003Y1126914
X1521003Y1107780
R02Y-0019134
X1524704Y1146047
X1524704Y1126914
X1524704Y1107780
X1524704Y1088646
X1521003Y1101402
X1526554Y1098213
X1519153Y1098213
X1524704Y1095024
X1521003Y1095024
X1526554Y1091835
X1519153Y1085457
X1526554Y1155614
X1524704Y1152425
X1524704Y1082268
X1521003Y1152425
X1526554Y1149236
X1519153Y1142858
X1524704Y1139669
X1521003Y1139669
X1526554Y1136480
X1519153Y1136480
X1524704Y1133292
X1521003Y1133292
X1526554Y1130102
X1521003Y1082268
X1519153Y1123725
X1524704Y1120536
X1521003Y1120536
X1526554Y1117347
X1519153Y1117347
X1524704Y1114158
X1521003Y1114158
X1526554Y1110969
X1519153Y1104591
X1524704Y1101402
X1526554Y1079079
X1524704Y1050378
X1519153Y1047189
X1519153Y1066323
X1524704Y1063134
X1521003Y1063134
X1526554Y1059945
X1519153Y1079079
X1524704Y1075890
X1521003Y1075890
X1526554Y1072701
X1526554Y1040811
X1519153Y1040811
X1521003Y1037622
X1524704Y1037622
X1526554Y1034433
X1519153Y1034433
X1521003Y1031244
X1521003Y1050378
X1519822Y1007182
X1519822Y0975292
X1519822Y0956158
R02Y-0019134
X1519822Y0898757
X1523523Y0968914
R03Y-0019134
X1523523Y0892379
X1517972Y0972103
R03Y-0019134
X1517972Y0895568
X1525373Y0972103
R03Y-0019134
X1525373Y0895568
X1517972Y0908324
X1523523Y0905134
X1519822Y0905134
X1525373Y0901946
X1517972Y0901946
X1523523Y0898757
X1519822Y0892379
X1519822Y0962536
X1525373Y0959347
X1525373Y0889190
X1517972Y0959347
X1523523Y0956158
X1519822Y0949780
X1525373Y0946591
X1517972Y0946591
X1523523Y0943402
X1519822Y0943402
X1525373Y0940213
X1517972Y0940213
X1523523Y0937024
X1517972Y0889190
X1519822Y0930646
X1525373Y0927457
X1517972Y0927457
X1523523Y0924268
X1519822Y0924268
X1525373Y0921079
X1517972Y0921079
X1523523Y0917890
X1519822Y0911512
X1525373Y0908324
X1523523Y0886001
X1517972Y0991237
X1523523Y0988048
X1519822Y0981670
X1525373Y0978481
X1517972Y0978481
X1523523Y0975292
X1519822Y0968914
X1525373Y0965725
X1517972Y0965725
X1523523Y0962536
X1517972Y1003993
X1525373Y1003993
X1523523Y1000804
X1519822Y1000804
X1517972Y0997615
X1525373Y0997615
X1523523Y0994426
X1519822Y0988048
X1523523Y1007182
X1525373Y1010371
X1517972Y0984859
X0332091Y1053568
X0333941Y1044001
X0332091Y1066324
X0339492Y1149237
X0339492Y1130103
X0339492Y1110970
R02Y-0019134
X0332091Y1142859
X0332091Y1123726
X0332091Y1104592
X0332091Y1085458
X0333941Y1069513
X0337642Y1146048
X0337642Y1126915
X0337642Y1107781
R02Y-0019134
X0333941Y1146048
X0333941Y1126915
X0333941Y1107781
X0333941Y1088647
X0337642Y1101403
X0332091Y1098214
X0339492Y1098214
X0333941Y1095025
X0337642Y1095025
X0332091Y1091836
X0339492Y1085458
X0332091Y1155615
X0333941Y1152426
X0333941Y1082269
X0337642Y1152426
X0332091Y1149237
X0339492Y1142859
X0333941Y1139670
X0337642Y1139670
X0332091Y1136481
X0339492Y1136481
X0333941Y1133293
X0337642Y1133293
X0332091Y1130103
X0337642Y1082269
X0339492Y1123726
X0333941Y1120537
X0337642Y1120537
X0332091Y1117348
X0339492Y1117348
X0333941Y1114159
X0337642Y1114159
X0332091Y1110970
X0339492Y1104592
X0333941Y1101403
X0332091Y1079080
X0333941Y1050379
X0339492Y1047190
X0339492Y1066324
X0333941Y1063135
X0337642Y1063135
X0332091Y1059946
X0339492Y1079080
X0333941Y1075891
X0337642Y1075891
X0332091Y1072702
X0332091Y1040812
X0339492Y1040812
X0337642Y1037623
X0333941Y1037623
X0332091Y1034434
X0339492Y1034434
X0337642Y1031245
X0337642Y1050379
X0336461Y1007183
X0336461Y0975293
X0336461Y0956159
R02Y-0019134
X0336461Y0898758
X0332760Y0968915
R03Y-0019134
X0332760Y0892380
X0338311Y0972104
R03Y-0019134
X0338311Y0895569
X0330910Y0972104
R03Y-0019134
X0330910Y0895569
X0338311Y0908325
X0332760Y0905135
X0336461Y0905135
X0330910Y0901947
X0338311Y0901947
X0332760Y0898758
X0336461Y0892380
X0336461Y0962537
X0330910Y0959348
X0330910Y0889191
X0338311Y0959348
X0332760Y0956159
X0336461Y0949781
X0330910Y0946592
X0338311Y0946592
X0332760Y0943403
X0336461Y0943403
X0330910Y0940214
X0338311Y0940214
X0332760Y0937025
X0338311Y0889191
X0336461Y0930647
X0330910Y0927458
X0338311Y0927458
X0332760Y0924269
X0336461Y0924269
X0330910Y0921080
X0338311Y0921080
X0332760Y0917891
X0336461Y0911513
X0330910Y0908325
X0332760Y0886002
X0336461Y0994427
X0330910Y0991238
X0336461Y0981671
X0330910Y0978482
X0338311Y0978482
X0332760Y0975293
X0336461Y0968915
X0330910Y0965726
X0338311Y0965726
X0332760Y0962537
X0338311Y1003994
X0330910Y1003994
X0332760Y1000805
X0336461Y1000805
X0338311Y0997616
X0330910Y0997616
X0332760Y0994427
X0336461Y0988049
X0332760Y1007183
X0330910Y1010372
X0338311Y0984860
X1308233Y1053567
X1310083Y1044000
X1308233Y1066323
X1315634Y1149236
X1315634Y1130102
X1315634Y1110969
R02Y-0019134
X1308233Y1142858
X1308233Y1123725
X1308233Y1104591
X1308233Y1085457
X1310083Y1069512
X1313784Y1146047
X1313784Y1126914
X1313784Y1107780
R02Y-0019134
X1310083Y1146047
X1310083Y1126914
X1310083Y1107780
X1310083Y1088646
X1313784Y1101402
X1308233Y1098213
X1315634Y1098213
X1310083Y1095024
X1313784Y1095024
X1308233Y1091835
X1315634Y1085457
X1308233Y1155614
X1310083Y1152425
X1310083Y1082268
X1313784Y1152425
X1308233Y1149236
X1315634Y1142858
X1310083Y1139669
X1313784Y1139669
X1308233Y1136480
X1315634Y1136480
X1310083Y1133292
X1313784Y1133292
X1308233Y1130102
X1313784Y1082268
X1315634Y1123725
X1310083Y1120536
X1313784Y1120536
X1308233Y1117347
X1315634Y1117347
X1310083Y1114158
X1313784Y1114158
X1308233Y1110969
X1315634Y1104591
X1310083Y1101402
X1308233Y1079079
X1310083Y1050378
X1315634Y1047189
X1315634Y1066323
X1310083Y1063134
X1313784Y1063134
X1308233Y1059945
X1315634Y1079079
X1310083Y1075890
X1313784Y1075890
X1308233Y1072701
X1308233Y1040811
X1315634Y1040811
X1313784Y1037622
X1310083Y1037622
X1308233Y1034433
X1315634Y1034433
X1313784Y1031244
X1313784Y1050378
X1312603Y1007182
X1312603Y0975292
X1312603Y0956158
R02Y-0019134
X1312603Y0898757
X1308902Y0968914
R03Y-0019134
X1308902Y0892379
X1314453Y0972103
R03Y-0019134
X1314453Y0895568
X1307052Y0972103
R03Y-0019134
X1307052Y0895568
X1314453Y0908324
X1308902Y0905134
X1312603Y0905134
X1307052Y0901946
X1314453Y0901946
X1308902Y0898757
X1312603Y0892379
X1312603Y0962536
X1307052Y0959347
X1307052Y0889190
X1314453Y0959347
X1308902Y0956158
X1312603Y0949780
X1307052Y0946591
X1314453Y0946591
X1308902Y0943402
X1312603Y0943402
X1307052Y0940213
X1314453Y0940213
X1308902Y0937024
X1314453Y0889190
X1312603Y0930646
X1307052Y0927457
X1314453Y0927457
X1308902Y0924268
X1312603Y0924268
X1307052Y0921079
X1314453Y0921079
X1308902Y0917890
X1312603Y0911512
X1307052Y0908324
X1308902Y0886001
X1312603Y0994426
X1307052Y0991237
X1312603Y0981670
X1307052Y0978481
X1314453Y0978481
X1308902Y0975292
X1312603Y0968914
X1307052Y0965725
X1314453Y0965725
X1308902Y0962536
X1314453Y1003993
X1307052Y1003993
X1308902Y1000804
X1312603Y1000804
X1314453Y0997615
X1307052Y0997615
X1308902Y0994426
X1312603Y0988048
X1308902Y1007182
X1307052Y1010371
X1314453Y0984859
X0484467Y0930647
X1371815Y0930646
X0473365Y0917891
X1382918Y0917890
X0473365Y0911513
X1382918Y0911512
X0473365Y0924269
X1382918Y0924268
X0462263Y0917891
X1394020Y0917890
X0462263Y0911513
X1394020Y0911512
X0462263Y0924269
X1394020Y0924268
X0453011Y0914702
X1403272Y0914701
X0453011Y0921080
X1403272Y0921079
X0495570Y0924269
X1360713Y0924268
X0495570Y0917891
X1360713Y0917890
X0495570Y0930647
X1360713Y0930646
X0484467Y0924269
X1371815Y0924268
X0484467Y0917891
X1371815Y0917890
X0484467Y0911513
X1371815Y0911512
X0453011Y0927458
X1403272Y0927457
X0480767Y0930647
X1375516Y0930646
X0469664Y0917891
X1386619Y0917890
X0469664Y0911513
X1386619Y0911512
X0469664Y0924269
X1386619Y0924268
X0458562Y0917891
X1397721Y0917890
X0458562Y0911513
X1397721Y0911512
X0458562Y0924269
X1397721Y0924268
X0449310Y0914702
X1406973Y0914701
X0449310Y0921080
X1406973Y0921079
X0491869Y0924269
X1364414Y0924268
X0491869Y0917891
X1364414Y0917890
X0491869Y0930647
X1364414Y0930646
X0480767Y0924269
X1375516Y0924268
X0480767Y0917891
X1375516Y0917890
X0480767Y0911513
X1375516Y0911512
X0449310Y0927458
X1406973Y0927457
M00
X0564279Y1624292
R08X-0012060
X0636639Y1624292
R05X-0012060
X0455739Y1624292
X0560879Y1624292
X0548819Y1624292
R07X-0012060
X0633239Y1624292
R05X-0012060
X0452339Y1624292
X0300106Y1624292
X0288046Y1624292
R07X-0012060
X0372466Y1624292
R05X-0012060
X0191566Y1624292
X0296706Y1624292
X0284646Y1624292
R07X-0012060
X0369066Y1624292
R05X-0012060
X0188166Y1624292
X1572153Y1657292
R08X-0012060
X1644513Y1657292
R05X-0012060
X1463613Y1657292
X1568753Y1657292
X1556693Y1657292
R07X-0012060
X1641113Y1657292
R05X-0012060
X1460213Y1657292
X1307979Y1657292
X1295919Y1657292
R07X-0012060
X1380339Y1657292
R05X-0012060
X1199439Y1657292
X1304579Y1657292
X1292519Y1657292
R07X-0012060
X1376939Y1657292
R05X-0012060
X1196039Y1657292
X0555505Y0112203
X0417486Y0127579
X0552105Y0112203
X0417486Y0124179
X0482255Y0129822
X0459056Y0095101
X0482255Y0133222
X0462456Y0095101
X0493780Y0131442
X0537318Y0047067
X0490380Y0131442
X0533918Y0047067
X0130553Y0069343
X0141557Y0075340
X0152553Y0069343
X0164761Y0075340
X0175761Y0069340
X0186757Y0075343
X0197761Y0069340
X0208895Y0075340
X0219891Y0069343
X0064557Y0069340
X0075553Y0075343
X0086557Y0069340
X0097557Y0075340
X0108557Y0069340
X0119557Y0075340
X0230895Y0075340
X0127153Y0069343
X0138157Y0075340
X0149153Y0069343
X0161361Y0075340
X0172361Y0069340
X0183357Y0075343
X0194361Y0069340
X0205495Y0075340
X0216491Y0069343
X0061157Y0069340
X0072153Y0075343
X0083157Y0069340
X0094157Y0075340
X0105157Y0069340
X0116157Y0075340
X0227495Y0075340
X1501698Y1485895
X1494998Y1495595
X1448098Y1485895
X1441398Y1495595
X1435160Y1513190
X1552668Y1527082
X1552668Y1517082
X1541898Y1485895
X1528498Y1485895
X1521798Y1495595
X1515098Y1505295
X1435160Y1538390
X1505098Y1485895
X1498398Y1495595
X1451498Y1485895
X1444798Y1495595
X1435160Y1516590
X1552668Y1530482
X1552668Y1513682
X1545298Y1485895
X1531898Y1485895
X1525198Y1495595
X1518498Y1505295
X1435160Y1534990
X0493824Y1452895
X0487124Y1462595
X0480424Y1472295
X0467024Y1452895
X0460324Y1462595
X0453624Y1472295
X0440224Y1452895
X0433524Y1462595
X0427286Y1480190
X0544794Y1494082
X0544794Y1484082
X0534024Y1452895
X0520624Y1452895
X0513924Y1462595
X0507224Y1472295
X0427286Y1505390
X0497224Y1452895
X0490524Y1462595
X0483824Y1472295
X0470424Y1452895
X0463724Y1462595
X0457024Y1472295
X0443624Y1452895
X0436924Y1462595
X0427286Y1483590
X0544794Y1497482
X0544794Y1480682
X0537424Y1452895
X0524024Y1452895
X0517324Y1462595
X0510624Y1472295
X0427286Y1501990
X1488298Y1505295
X1474898Y1485895
X1468198Y1495595
X1461498Y1505295
X1491698Y1505295
X1478298Y1485895
X1471598Y1495595
X1464898Y1505295
X1591794Y0026477
X1598899Y0019541
X1627660Y0026477
X1634765Y0019541
X1641833Y0026477
X1648938Y0019541
X1671794Y0026477
X1678899Y0019541
X1685967Y0026477
X1549274Y0026477
X1556379Y0019541
X1563447Y0026477
X1570552Y0019541
X1577620Y0026477
X1584725Y0019541
X1693072Y0019541
X1595194Y0026477
X1602299Y0019541
X1631060Y0026477
X1638165Y0019541
X1645233Y0026477
X1652338Y0019541
X1675194Y0026477
X1682299Y0019541
X1689367Y0026477
X1552674Y0026477
X1559779Y0019541
X1566847Y0026477
X1573952Y0019541
X1581020Y0026477
X1588125Y0019541
X1696472Y0019541
X0812000Y1064706
X0795858Y1051320
X0812000Y1084785
X0795858Y1238722
R04Y-0036811
X0812000Y1232029
R03Y-0036811
X0812000Y1088131
X0795858Y1235375
R04Y-0036811
X0812000Y1235375
R03Y-0036811
X0812000Y1151714
X0812000Y1145021
X0795858Y1141675
X0795858Y1134982
X0812000Y1138328
X0812000Y1131635
X0795858Y1118249
X0795858Y1252108
X0795858Y1245415
X0795858Y1111556
X0812000Y1248761
X0812000Y1242068
X0795858Y1228682
X0795858Y1221989
X0812000Y1225336
X0812000Y1218643
X0795858Y1215297
X0795858Y1208604
X0812000Y1211950
X0812000Y1205257
X0812000Y1114903
X0795858Y1191871
X0795858Y1185178
X0812000Y1188525
X0812000Y1181832
X0795858Y1178486
X0795858Y1171793
X0812000Y1175139
X0812000Y1168446
X0795858Y1155060
X0795858Y1148367
X0812000Y1108210
X0795858Y1058013
X0812000Y1054667
X0795858Y1081438
X0795858Y1074745
X0812000Y1078092
X0812000Y1071399
X0795858Y1104863
X0795858Y1098171
X0812000Y1101517
X0812000Y1094824
X0812000Y1047974
X0795858Y1044627
X0812000Y1041281
X0795858Y1037934
X0812000Y1034588
X0795858Y1031241
X0812000Y1027895
X0812000Y1061360
X0812000Y1001123
X0795858Y0944234
X0795858Y0907423
X0795858Y0870611
R02Y-0036811
X0812000Y0937541
R04Y-0036811
X0795858Y0940887
R04Y-0036811
X0812000Y0940887
R04Y-0036811
X0812000Y0820415
X0812000Y0813722
X0795858Y0810375
X0795858Y0803682
X0812000Y0807029
X0812000Y0800336
X0795858Y0786950
X0795858Y0920808
X0795858Y0914115
X0795858Y0780257
X0812000Y0917462
X0812000Y0910769
X0795858Y0897383
X0795858Y0890690
X0812000Y0894037
X0812000Y0887344
X0795858Y0883997
X0795858Y0877304
X0812000Y0880651
X0812000Y0873958
X0812000Y0783604
X0795858Y0860572
X0795858Y0853879
X0812000Y0857226
X0812000Y0850533
X0795858Y0847186
X0795858Y0840493
X0812000Y0843840
X0812000Y0837147
X0795858Y0823761
X0795858Y0817068
X0812000Y0776911
X0795858Y0971005
X0812000Y0967659
X0795858Y0957619
X0795858Y0950926
X0812000Y0954273
X0812000Y0947580
X0795858Y0934194
X0795858Y0927501
X0812000Y0930848
X0812000Y0924155
X0812000Y0994430
X0795858Y0991084
X0812000Y0987737
X0795858Y0984391
X0812000Y0981045
X0795858Y0977698
X0812000Y0974352
X0795858Y0964312
X0795858Y0997777
X0795858Y1001123
X1788142Y1064705
X1772000Y1051319
X1788142Y1084784
X1772000Y1238721
R04Y-0036811
X1788142Y1232028
R03Y-0036811
X1788142Y1088130
X1772000Y1235374
R04Y-0036811
X1788142Y1235374
R03Y-0036811
X1788142Y1151713
X1788142Y1145020
X1772000Y1141674
X1772000Y1134981
X1788142Y1138327
X1788142Y1131634
X1772000Y1118248
X1772000Y1252107
X1772000Y1245414
X1772000Y1111555
X1788142Y1248760
X1788142Y1242067
X1772000Y1228681
X1772000Y1221988
X1788142Y1225335
X1788142Y1218642
X1772000Y1215296
X1772000Y1208603
X1788142Y1211949
X1788142Y1205256
X1788142Y1114902
X1772000Y1191870
X1772000Y1185177
X1788142Y1188524
X1788142Y1181831
X1772000Y1178485
X1772000Y1171792
X1788142Y1175138
X1788142Y1168445
X1772000Y1155059
X1772000Y1148366
X1788142Y1108209
X1772000Y1058012
X1788142Y1054666
X1772000Y1081437
X1772000Y1074744
X1788142Y1078091
X1788142Y1071398
X1772000Y1104862
X1772000Y1098170
X1788142Y1101516
X1788142Y1094823
X1788142Y1047973
X1772000Y1044626
X1788142Y1041280
X1772000Y1037933
X1788142Y1034587
X1772000Y1031240
X1788142Y1027894
X1788142Y1061359
X1788142Y1001122
X1772000Y0944233
X1772000Y0907422
X1772000Y0870610
R02Y-0036811
X1788142Y0937540
R04Y-0036811
X1772000Y0940886
R04Y-0036811
X1788142Y0940886
R04Y-0036811
X1788142Y0820414
X1788142Y0813721
X1772000Y0810374
X1772000Y0803681
X1788142Y0807028
X1788142Y0800335
X1772000Y0786949
X1772000Y0920807
X1772000Y0914114
X1772000Y0780256
X1788142Y0917461
X1788142Y0910768
X1772000Y0897382
X1772000Y0890689
X1788142Y0894036
X1788142Y0887343
X1772000Y0883996
X1772000Y0877303
X1788142Y0880650
X1788142Y0873957
X1788142Y0783603
X1772000Y0860571
X1772000Y0853878
X1788142Y0857225
X1788142Y0850532
X1772000Y0847185
X1772000Y0840492
X1788142Y0843839
X1788142Y0837146
X1772000Y0823760
X1772000Y0817067
X1788142Y0776910
X1772000Y0971004
X1788142Y0967658
X1772000Y0957618
X1772000Y0950925
X1788142Y0954272
X1788142Y0947579
X1772000Y0934193
X1772000Y0927500
X1788142Y0930847
X1788142Y0924154
X1788142Y0994429
X1772000Y0991083
X1788142Y0987736
X1772000Y0984390
X1788142Y0981044
X1772000Y0977697
X1788142Y0974351
X1772000Y0964311
X1772000Y0997776
X1772000Y1001122
X0085465Y1064706
X0069323Y1051320
X0085465Y1084785
X0069323Y1238722
R04Y-0036811
X0085465Y1232029
R03Y-0036811
X0085465Y1088131
X0069323Y1235375
R04Y-0036811
X0085465Y1235375
R03Y-0036811
X0085465Y1151714
X0085465Y1145021
X0069323Y1141675
X0069323Y1134982
X0085465Y1138328
X0085465Y1131635
X0069323Y1118249
X0069323Y1252108
X0069323Y1245415
X0069323Y1111556
X0085465Y1248761
X0085465Y1242068
X0069323Y1228682
X0069323Y1221989
X0085465Y1225336
X0085465Y1218643
X0069323Y1215297
X0069323Y1208604
X0085465Y1211950
X0085465Y1205257
X0085465Y1114903
X0069323Y1191871
X0069323Y1185178
X0085465Y1188525
X0085465Y1181832
X0069323Y1178486
X0069323Y1171793
X0085465Y1175139
X0085465Y1168446
X0069323Y1155060
X0069323Y1148367
X0085465Y1108210
X0069323Y1058013
X0085465Y1054667
X0069323Y1081438
X0069323Y1074745
X0085465Y1078092
X0085465Y1071399
X0069323Y1104863
X0069323Y1098171
X0085465Y1101517
X0085465Y1094824
X0085465Y1047974
X0069323Y1044627
X0085465Y1041281
X0069323Y1037934
X0085465Y1034588
X0069323Y1031241
X0085465Y1027895
X0085465Y1061360
X0085465Y1001123
X0069323Y0944234
X0069323Y0907423
X0069323Y0870611
R02Y-0036811
X0085465Y0937541
R04Y-0036811
X0069323Y0940887
R04Y-0036811
X0085465Y0940887
R04Y-0036811
X0085465Y0820415
X0085465Y0813722
X0069323Y0810375
X0069323Y0803682
X0085465Y0807029
X0085465Y0800336
X0069323Y0786950
X0069323Y0920808
X0069323Y0914115
X0069323Y0780257
X0085465Y0917462
X0085465Y0910769
X0069323Y0897383
X0069323Y0890690
X0085465Y0894037
X0085465Y0887344
X0069323Y0883997
X0069323Y0877304
X0085465Y0880651
X0085465Y0873958
X0085465Y0783604
X0069323Y0860572
X0069323Y0853879
X0085465Y0857226
X0085465Y0850533
X0069323Y0847186
X0069323Y0840493
X0085465Y0843840
X0085465Y0837147
X0069323Y0823761
X0069323Y0817068
X0085465Y0776911
X0069323Y0971005
X0085465Y0967659
X0069323Y0957619
X0069323Y0950926
X0085465Y0954273
X0085465Y0947580
X0069323Y0934194
X0069323Y0927501
X0085465Y0930848
X0085465Y0924155
X0085465Y0994430
X0069323Y0991084
X0085465Y0987737
X0069323Y0984391
X0085465Y0981045
X0069323Y0977698
X0085465Y0974352
X0069323Y0964312
X0069323Y0997777
X0069323Y1001123
X1061607Y1064705
X1045465Y1051319
X1061607Y1084784
X1045465Y1238721
R04Y-0036811
X1061607Y1232028
R03Y-0036811
X1061607Y1088130
X1045465Y1235374
R04Y-0036811
X1061607Y1235374
R03Y-0036811
X1061607Y1151713
X1061607Y1145020
X1045465Y1141674
X1045465Y1134981
X1061607Y1138327
X1061607Y1131634
X1045465Y1118248
X1045465Y1252107
X1045465Y1245414
X1045465Y1111555
X1061607Y1248760
X1061607Y1242067
X1045465Y1228681
X1045465Y1221988
X1061607Y1225335
X1061607Y1218642
X1045465Y1215296
X1045465Y1208603
X1061607Y1211949
X1061607Y1205256
X1061607Y1114902
X1045465Y1191870
X1045465Y1185177
X1061607Y1188524
X1061607Y1181831
X1045465Y1178485
X1045465Y1171792
X1061607Y1175138
X1061607Y1168445
X1045465Y1155059
X1045465Y1148366
X1061607Y1108209
X1045465Y1058012
X1061607Y1054666
X1045465Y1081437
X1045465Y1074744
X1061607Y1078091
X1061607Y1071398
X1045465Y1104862
X1045465Y1098170
X1061607Y1101516
X1061607Y1094823
X1061607Y1047973
X1045465Y1044626
X1061607Y1041280
X1045465Y1037933
X1061607Y1034587
X1045465Y1031240
X1061607Y1027894
X1061607Y1061359
X1061607Y1001122
X1045465Y0944233
X1045465Y0907422
X1045465Y0870610
R02Y-0036811
X1061607Y0937540
R04Y-0036811
X1045465Y0940886
R04Y-0036811
X1061607Y0940886
R04Y-0036811
X1061607Y0820414
X1061607Y0813721
X1045465Y0810374
X1045465Y0803681
X1061607Y0807028
X1061607Y0800335
X1045465Y0786949
X1045465Y0920807
X1045465Y0914114
X1045465Y0780256
X1061607Y0917461
X1061607Y0910768
X1045465Y0897382
X1045465Y0890689
X1061607Y0894036
X1061607Y0887343
X1045465Y0883996
X1045465Y0877303
X1061607Y0880650
X1061607Y0873957
X1061607Y0783603
X1045465Y0860571
X1045465Y0853878
X1061607Y0857225
X1061607Y0850532
X1045465Y0847185
X1045465Y0840492
X1061607Y0843839
X1061607Y0837146
X1045465Y0823760
X1045465Y0817067
X1061607Y0776910
X1045465Y0971004
X1061607Y0967658
X1045465Y0957618
X1045465Y0950925
X1061607Y0954272
X1061607Y0947579
X1045465Y0934193
X1045465Y0927500
X1061607Y0930847
X1061607Y0924154
X1061607Y0994429
X1045465Y0991083
X1061607Y0987736
X1045465Y0984390
X1061607Y0981044
X1045465Y0977697
X1061607Y0974351
X1045465Y0964311
X1045465Y0997776
X1045465Y1001122
M00
X0337205Y1700354
X0352953Y1700354
X0329331Y1696417
X0337205Y1695629
X0345079Y1696417
X0352953Y1695629
X0329331Y1691692
X0345079Y1691692
X0305709Y1700354
X0321457Y1700354
X0297835Y1696417
X0305709Y1695629
X0313583Y1696417
X0321457Y1695629
X0297835Y1691692
X0313583Y1691692
X0270275Y1700354
X0286023Y1700354
X0262401Y1696417
X0270275Y1695629
X0278149Y1696417
X0286023Y1695629
X0262401Y1691692
X0278149Y1691692
X0238779Y1700354
X0254527Y1700354
X0230905Y1696417
X0238779Y1695629
X0246653Y1696417
X0254527Y1695629
X0230905Y1691692
X0246653Y1691692
X0534448Y1700354
X0550196Y1700354
X0526574Y1696417
X0534448Y1695629
X0542322Y1696417
X0550196Y1695629
X0526574Y1691692
X0542322Y1691692
X0502952Y1700354
X0518700Y1700354
X0495078Y1696417
X0502952Y1695629
X0510826Y1696417
X0518700Y1695629
X0495078Y1691692
X0510826Y1691692
X0601378Y1700354
X0617126Y1700354
X0593504Y1696417
X0601378Y1695629
X0609252Y1696417
X0617126Y1695629
X0593504Y1691692
X0609252Y1691692
X0569882Y1700354
X0585630Y1700354
X0562008Y1696417
X0569882Y1695629
X0577756Y1696417
X0585630Y1695629
X0562008Y1691692
X0577756Y1691692
X1345078Y1700354
X1360826Y1700354
X1337204Y1696417
X1345078Y1695629
X1352952Y1696417
X1360826Y1695629
X1337204Y1691692
X1352952Y1691692
X1313582Y1700354
X1329330Y1700354
X1305708Y1696417
X1313582Y1695629
X1321456Y1696417
X1329330Y1695629
X1305708Y1691692
X1321456Y1691692
X1278148Y1700354
X1293896Y1700354
X1270274Y1696417
X1278148Y1695629
X1286022Y1696417
X1293896Y1695629
X1270274Y1691692
X1286022Y1691692
X1246652Y1700354
X1262400Y1700354
X1238778Y1696417
X1246652Y1695629
X1254526Y1696417
X1262400Y1695629
X1238778Y1691692
X1254526Y1691692
X1542322Y1700354
X1558070Y1700354
X1534448Y1696417
X1542322Y1695629
X1550196Y1696417
X1558070Y1695629
X1534448Y1691692
X1550196Y1691692
X1510826Y1700354
X1526574Y1700354
X1502952Y1696417
X1510826Y1695629
X1518700Y1696417
X1526574Y1695629
X1502952Y1691692
X1518700Y1691692
X1609252Y1700354
X1625000Y1700354
X1601378Y1696417
X1609252Y1695629
X1617126Y1696417
X1625000Y1695629
X1601378Y1691692
X1617126Y1691692
X1577756Y1700354
X1593504Y1700354
X1569882Y1696417
X1577756Y1695629
X1585630Y1696417
X1593504Y1695629
X1569882Y1691692
X1585630Y1691692
M30
